(kicad_pcb
	(version 20260206)
	(generator "pcbnew")
	(generator_version "10.0")
	(general
		(thickness 1.6)
		(legacy_teardrops no)
	)
	(paper "A4")
	(title_block
		(title "01162023_DA0F0TEBIF0_F0T_Expander_BD_F_brd_V02_OCP.brd")
		(comment 1 "Grand Teton / footprints 2313-2319 of 9728")
	)
	(layers
		(0 "F.Cu" signal "TOP")
		(4 "In1.Cu" signal "GND")
		(6 "In2.Cu" signal "VCC")
		(8 "In3.Cu" signal "VCC1")
		(10 "In4.Cu" signal "GND1")
		(12 "In5.Cu" signal "IN1")
		(14 "In6.Cu" signal "GND2")
		(16 "In7.Cu" signal "IN2")
		(18 "In8.Cu" signal "GND3")
		(20 "In9.Cu" signal "IN3")
		(22 "In10.Cu" signal "GND4")
		(24 "In11.Cu" signal "IN4")
		(26 "In12.Cu" signal "GND5")
		(28 "In13.Cu" signal "IN5")
		(30 "In14.Cu" signal "GND6")
		(32 "In15.Cu" signal "IN6")
		(34 "In16.Cu" signal "GND7")
		(2 "B.Cu" signal "BOTTOM")
		(9 "F.Adhes" user "F.Adhesive")
		(11 "B.Adhes" user "B.Adhesive")
		(13 "F.Paste" user "Package Geometry/Pastemask Top")
		(15 "B.Paste" user "Package Geometry/Pastemask Bottom")
		(5 "F.SilkS" user "Ref Des/Silkscreen Top")
		(7 "B.SilkS" user "Ref Des/Silkscreen Bottom")
		(1 "F.Mask" user "Board Geometry/Soldermask Top")
		(3 "B.Mask" user "Board Geometry/Soldermask Bottom")
		(17 "Dwgs.User" user "User.Drawings")
		(19 "Cmts.User" user "User.Comments")
		(21 "Eco1.User" user "User.Eco1")
		(23 "Eco2.User" user "User.Eco2")
		(25 "Edge.Cuts" user "Board Geometry/Outline")
		(27 "Margin" user)
		(31 "F.CrtYd" user "Package Geometry/Place Bound Top")
		(29 "B.CrtYd" user "Package Geometry/Place Bound Bottom")
		(35 "F.Fab" user "Ref Des/Assembly Top")
		(33 "B.Fab" user "Ref Des/Assembly Bottom")
	)
	(footprint ""
		(layer "F.Cu")
		(at 121.13514 -96.034606)
		(property "Reference" "R1552"
			(at 0 0 0)
			(layer "F.SilkS")
			(hide yes)
			(effects
				(font
					(size 1.27 1.27)
				)
			)
		)
		(property "Value" ""
			(at 0 0 0)
			(layer "F.Fab")
			(effects
				(font
					(size 1.27 1.27)
				)
			)
		)
		(duplicate_pad_numbers_are_jumpers no)
		(fp_line
			(start -0.7874 -0.4064)
			(end 0.7874 -0.4064)
			(stroke
				(width 0.1524)
				(type default)
			)
			(layer "F.SilkS")
		)
		(fp_line
			(start -0.7874 0.4064)
			(end -0.7874 -0.4064)
			(stroke
				(width 0.1524)
				(type default)
			)
			(layer "F.SilkS")
		)
		(fp_line
			(start 0.7874 -0.4064)
			(end 0.7874 0.4064)
			(stroke
				(width 0.1524)
				(type default)
			)
			(layer "F.SilkS")
		)
		(fp_line
			(start 0.7874 0.4064)
			(end -0.7874 0.4064)
			(stroke
				(width 0.1524)
				(type default)
			)
			(layer "F.SilkS")
		)
		(fp_line
			(start -0.67945 -0.305054)
			(end -0.12065 -0.305054)
			(stroke
				(width 0.1)
				(type default)
			)
			(layer "F.Fab")
		)
		(fp_line
			(start -0.67945 0.3048)
			(end -0.67945 -0.305054)
			(stroke
				(width 0.1)
				(type default)
			)
			(layer "F.Fab")
		)
		(fp_line
			(start -0.12065 -0.305054)
			(end -0.12065 -0.2794)
			(stroke
				(width 0.1)
				(type default)
			)
			(layer "F.Fab")
		)
		(fp_line
			(start -0.12065 -0.2794)
			(end 0.12065 -0.2794)
			(stroke
				(width 0.1)
				(type default)
			)
			(layer "F.Fab")
		)
		(fp_line
			(start -0.12065 0.2794)
			(end -0.12065 0.3048)
			(stroke
				(width 0.1)
				(type default)
			)
			(layer "F.Fab")
		)
		(fp_line
			(start -0.12065 0.3048)
			(end -0.67945 0.3048)
			(stroke
				(width 0.1)
				(type default)
			)
			(layer "F.Fab")
		)
		(fp_line
			(start 0.120396 0.2794)
			(end -0.12065 0.2794)
			(stroke
				(width 0.1)
				(type default)
			)
			(layer "F.Fab")
		)
		(fp_line
			(start 0.120396 0.3048)
			(end 0.120396 0.2794)
			(stroke
				(width 0.1)
				(type default)
			)
			(layer "F.Fab")
		)
		(fp_line
			(start 0.12065 -0.3048)
			(end 0.67945 -0.3048)
			(stroke
				(width 0.1)
				(type default)
			)
			(layer "F.Fab")
		)
		(fp_line
			(start 0.12065 -0.2794)
			(end 0.12065 -0.3048)
			(stroke
				(width 0.1)
				(type default)
			)
			(layer "F.Fab")
		)
		(fp_line
			(start 0.67945 -0.3048)
			(end 0.67945 0.3048)
			(stroke
				(width 0.1)
				(type default)
			)
			(layer "F.Fab")
		)
		(fp_line
			(start 0.67945 0.3048)
			(end 0.120396 0.3048)
			(stroke
				(width 0.1)
				(type default)
			)
			(layer "F.Fab")
		)
		(pad "1" smd circle
			(at -0.40005 0)
			(size 0 0)
			(layers "F.Cu" "F.Mask" "F.Paste")
			(net "P3V3_AUX")
		)
		(pad "2" smd circle
			(at 0.40005 0)
			(size 0 0)
			(layers "F.Cu" "F.Mask" "F.Paste")
			(net "SMB_BIC_I2C9_MUX0_SSD0_R_SCL")
		)
	)
	(footprint ""
		(layer "F.Cu")
		(at 154.666442 -250.070874 -90)
		(property "Reference" "R1268"
			(at 0 0 270)
			(layer "F.SilkS")
			(hide yes)
			(effects
				(font
					(size 1.27 1.27)
				)
			)
		)
		(property "Value" ""
			(at 0 0 270)
			(layer "F.Fab")
			(effects
				(font
					(size 1.27 1.27)
				)
			)
		)
		(duplicate_pad_numbers_are_jumpers no)
		(fp_line
			(start -0.7874 0.4064)
			(end -0.7874 -0.4064)
			(stroke
				(width 0.1524)
				(type default)
			)
			(layer "F.SilkS")
		)
		(fp_line
			(start 0.7874 0.4064)
			(end -0.7874 0.4064)
			(stroke
				(width 0.1524)
				(type default)
			)
			(layer "F.SilkS")
		)
		(fp_line
			(start -0.7874 -0.4064)
			(end 0.7874 -0.4064)
			(stroke
				(width 0.1524)
				(type default)
			)
			(layer "F.SilkS")
		)
		(fp_line
			(start 0.7874 -0.4064)
			(end 0.7874 0.4064)
			(stroke
				(width 0.1524)
				(type default)
			)
			(layer "F.SilkS")
		)
		(fp_line
			(start -0.67945 0.3048)
			(end -0.67945 -0.305054)
			(stroke
				(width 0.1)
				(type default)
			)
			(layer "F.Fab")
		)
		(fp_line
			(start -0.12065 0.3048)
			(end -0.67945 0.3048)
			(stroke
				(width 0.1)
				(type default)
			)
			(layer "F.Fab")
		)
		(fp_line
			(start 0.120396 0.3048)
			(end 0.120396 0.2794)
			(stroke
				(width 0.1)
				(type default)
			)
			(layer "F.Fab")
		)
		(fp_line
			(start 0.67945 0.3048)
			(end 0.120396 0.3048)
			(stroke
				(width 0.1)
				(type default)
			)
			(layer "F.Fab")
		)
		(fp_line
			(start -0.12065 0.2794)
			(end -0.12065 0.3048)
			(stroke
				(width 0.1)
				(type default)
			)
			(layer "F.Fab")
		)
		(fp_line
			(start 0.120396 0.2794)
			(end -0.12065 0.2794)
			(stroke
				(width 0.1)
				(type default)
			)
			(layer "F.Fab")
		)
		(fp_line
			(start -0.12065 -0.2794)
			(end 0.12065 -0.2794)
			(stroke
				(width 0.1)
				(type default)
			)
			(layer "F.Fab")
		)
		(fp_line
			(start 0.12065 -0.2794)
			(end 0.12065 -0.3048)
			(stroke
				(width 0.1)
				(type default)
			)
			(layer "F.Fab")
		)
		(fp_line
			(start 0.12065 -0.3048)
			(end 0.67945 -0.3048)
			(stroke
				(width 0.1)
				(type default)
			)
			(layer "F.Fab")
		)
		(fp_line
			(start 0.67945 -0.3048)
			(end 0.67945 0.3048)
			(stroke
				(width 0.1)
				(type default)
			)
			(layer "F.Fab")
		)
		(fp_line
			(start -0.67945 -0.305054)
			(end -0.12065 -0.305054)
			(stroke
				(width 0.1)
				(type default)
			)
			(layer "F.Fab")
		)
		(fp_line
			(start -0.12065 -0.305054)
			(end -0.12065 -0.2794)
			(stroke
				(width 0.1)
				(type default)
			)
			(layer "F.Fab")
		)
		(pad "1" smd circle
			(at -0.40005 0 270)
			(size 0 0)
			(layers "F.Cu" "F.Mask" "F.Paste")
			(net "PEX1_DBG_MODE4")
		)
		(pad "2" smd circle
			(at 0.40005 0 270)
			(size 0 0)
			(layers "F.Cu" "F.Mask" "F.Paste")
			(net "P1V8_PEX")
		)
	)
	(footprint ""
		(layer "F.Cu")
		(at 409.49499 -59.577986 90)
		(property "Reference" "PC579"
			(at 0 0 90)
			(layer "F.SilkS")
			(hide yes)
			(effects
				(font
					(size 1.27 1.27)
				)
			)
		)
		(property "Value" ""
			(at 0 0 90)
			(layer "F.Fab")
			(effects
				(font
					(size 1.27 1.27)
				)
			)
		)
		(duplicate_pad_numbers_are_jumpers no)
		(fp_line
			(start 0.7874 -0.4064)
			(end 0.7874 0.4064)
			(stroke
				(width 0.1524)
				(type default)
			)
			(layer "F.SilkS")
		)
		(fp_line
			(start -0.7874 -0.4064)
			(end 0.7874 -0.4064)
			(stroke
				(width 0.1524)
				(type default)
			)
			(layer "F.SilkS")
		)
		(fp_line
			(start 0.7874 0.4064)
			(end -0.7874 0.4064)
			(stroke
				(width 0.1524)
				(type default)
			)
			(layer "F.SilkS")
		)
		(fp_line
			(start -0.7874 0.4064)
			(end -0.7874 -0.4064)
			(stroke
				(width 0.1524)
				(type default)
			)
			(layer "F.SilkS")
		)
		(fp_line
			(start -0.12065 -0.305054)
			(end -0.12065 -0.2794)
			(stroke
				(width 0.1)
				(type default)
			)
			(layer "F.Fab")
		)
		(fp_line
			(start -0.67945 -0.305054)
			(end -0.12065 -0.305054)
			(stroke
				(width 0.1)
				(type default)
			)
			(layer "F.Fab")
		)
		(fp_line
			(start 0.67945 -0.3048)
			(end 0.67945 0.3048)
			(stroke
				(width 0.1)
				(type default)
			)
			(layer "F.Fab")
		)
		(fp_line
			(start 0.12065 -0.3048)
			(end 0.67945 -0.3048)
			(stroke
				(width 0.1)
				(type default)
			)
			(layer "F.Fab")
		)
		(fp_line
			(start 0.12065 -0.2794)
			(end 0.12065 -0.3048)
			(stroke
				(width 0.1)
				(type default)
			)
			(layer "F.Fab")
		)
		(fp_line
			(start -0.12065 -0.2794)
			(end 0.12065 -0.2794)
			(stroke
				(width 0.1)
				(type default)
			)
			(layer "F.Fab")
		)
		(fp_line
			(start 0.120396 0.2794)
			(end -0.12065 0.2794)
			(stroke
				(width 0.1)
				(type default)
			)
			(layer "F.Fab")
		)
		(fp_line
			(start -0.12065 0.2794)
			(end -0.12065 0.3048)
			(stroke
				(width 0.1)
				(type default)
			)
			(layer "F.Fab")
		)
		(fp_line
			(start 0.67945 0.3048)
			(end 0.120396 0.3048)
			(stroke
				(width 0.1)
				(type default)
			)
			(layer "F.Fab")
		)
		(fp_line
			(start 0.120396 0.3048)
			(end 0.120396 0.2794)
			(stroke
				(width 0.1)
				(type default)
			)
			(layer "F.Fab")
		)
		(fp_line
			(start -0.12065 0.3048)
			(end -0.67945 0.3048)
			(stroke
				(width 0.1)
				(type default)
			)
			(layer "F.Fab")
		)
		(fp_line
			(start -0.67945 0.3048)
			(end -0.67945 -0.305054)
			(stroke
				(width 0.1)
				(type default)
			)
			(layer "F.Fab")
		)
		(pad "1" smd circle
			(at -0.40005 0 90)
			(size 0 0)
			(layers "F.Cu" "F.Mask" "F.Paste")
			(net "P3V3_SSD14_SS")
		)
		(pad "2" smd circle
			(at 0.40005 0 90)
			(size 0 0)
			(layers "F.Cu" "F.Mask" "F.Paste")
			(net "GND")
		)
	)
	(footprint ""
		(layer "F.Cu")
		(at 431.946812 -356.244906 90)
		(property "Reference" "C2462"
			(at 0 0 90)
			(layer "F.SilkS")
			(hide yes)
			(effects
				(font
					(size 1.27 1.27)
				)
			)
		)
		(property "Value" ""
			(at 0 0 90)
			(layer "F.Fab")
			(effects
				(font
					(size 1.27 1.27)
				)
			)
		)
		(duplicate_pad_numbers_are_jumpers no)
		(fp_line
			(start 0.299974 -0.150114)
			(end 0.299974 0.150114)
			(stroke
				(width 0.1)
				(type default)
			)
			(layer "F.Fab")
		)
		(fp_line
			(start -0.299974 -0.150114)
			(end 0.299974 -0.150114)
			(stroke
				(width 0.1)
				(type default)
			)
			(layer "F.Fab")
		)
		(fp_line
			(start 0.299974 0.150114)
			(end -0.299974 0.150114)
			(stroke
				(width 0.1)
				(type default)
			)
			(layer "F.Fab")
		)
		(fp_line
			(start -0.299974 0.150114)
			(end -0.299974 -0.150114)
			(stroke
				(width 0.1)
				(type default)
			)
			(layer "F.Fab")
		)
		(pad "1" smd rect
			(at -0.2667 0 90)
			(size 0.3048 0.381)
			(layers "F.Cu" "F.Mask" "F.Paste")
			(net "P5E_PEX3_STN4_TX_DN<68>")
		)
		(pad "2" smd rect
			(at 0.2667 0 90)
			(size 0.3048 0.381)
			(layers "F.Cu" "F.Mask" "F.Paste")
			(net "P5E_PEX3_STN4_TX_C_DN<68>")
		)
	)
	(footprint ""
		(layer "F.Cu")
		(at 143.30045 -256.478786)
		(property "Reference" "C3240"
			(at 0 0 0)
			(layer "F.SilkS")
			(hide yes)
			(effects
				(font
					(size 1.27 1.27)
				)
			)
		)
		(property "Value" ""
			(at 0 0 0)
			(layer "F.Fab")
			(effects
				(font
					(size 1.27 1.27)
				)
			)
		)
		(duplicate_pad_numbers_are_jumpers no)
		(fp_line
			(start -0.299974 -0.150114)
			(end 0.299974 -0.150114)
			(stroke
				(width 0.1)
				(type default)
			)
			(layer "F.Fab")
		)
		(fp_line
			(start -0.299974 0.150114)
			(end -0.299974 -0.150114)
			(stroke
				(width 0.1)
				(type default)
			)
			(layer "F.Fab")
		)
		(fp_line
			(start 0.299974 -0.150114)
			(end 0.299974 0.150114)
			(stroke
				(width 0.1)
				(type default)
			)
			(layer "F.Fab")
		)
		(fp_line
			(start 0.299974 0.150114)
			(end -0.299974 0.150114)
			(stroke
				(width 0.1)
				(type default)
			)
			(layer "F.Fab")
		)
		(pad "1" smd rect
			(at -0.2667 0)
			(size 0.3048 0.381)
			(layers "F.Cu" "F.Mask" "F.Paste")
			(net "P1V8_PLL0_PEX1")
		)
		(pad "2" smd rect
			(at 0.2667 0)
			(size 0.3048 0.381)
			(layers "F.Cu" "F.Mask" "F.Paste")
			(net "GND")
		)
	)
	(footprint ""
		(layer "F.Cu")
		(at 436.95239 -116.416836 180)
		(property "Reference" "PC912"
			(at 0 0 180)
			(layer "F.SilkS")
			(hide yes)
			(effects
				(font
					(size 1.27 1.27)
				)
			)
		)
		(property "Value" ""
			(at 0 0 180)
			(layer "F.Fab")
			(effects
				(font
					(size 1.27 1.27)
				)
			)
		)
		(duplicate_pad_numbers_are_jumpers no)
		(fp_line
			(start 0.7874 0.4064)
			(end -0.7874 0.4064)
			(stroke
				(width 0.1524)
				(type default)
			)
			(layer "F.SilkS")
		)
		(fp_line
			(start 0.7874 -0.4064)
			(end 0.7874 0.4064)
			(stroke
				(width 0.1524)
				(type default)
			)
			(layer "F.SilkS")
		)
		(fp_line
			(start -0.7874 0.4064)
			(end -0.7874 -0.4064)
			(stroke
				(width 0.1524)
				(type default)
			)
			(layer "F.SilkS")
		)
		(fp_line
			(start -0.7874 -0.4064)
			(end 0.7874 -0.4064)
			(stroke
				(width 0.1524)
				(type default)
			)
			(layer "F.SilkS")
		)
		(fp_line
			(start 0.67945 0.3048)
			(end 0.120396 0.3048)
			(stroke
				(width 0.1)
				(type default)
			)
			(layer "F.Fab")
		)
		(fp_line
			(start 0.67945 -0.3048)
			(end 0.67945 0.3048)
			(stroke
				(width 0.1)
				(type default)
			)
			(layer "F.Fab")
		)
		(fp_line
			(start 0.12065 -0.2794)
			(end 0.12065 -0.3048)
			(stroke
				(width 0.1)
				(type default)
			)
			(layer "F.Fab")
		)
		(fp_line
			(start 0.12065 -0.3048)
			(end 0.67945 -0.3048)
			(stroke
				(width 0.1)
				(type default)
			)
			(layer "F.Fab")
		)
		(fp_line
			(start 0.120396 0.3048)
			(end 0.120396 0.2794)
			(stroke
				(width 0.1)
				(type default)
			)
			(layer "F.Fab")
		)
		(fp_line
			(start 0.120396 0.2794)
			(end -0.12065 0.2794)
			(stroke
				(width 0.1)
				(type default)
			)
			(layer "F.Fab")
		)
		(fp_line
			(start -0.12065 0.3048)
			(end -0.67945 0.3048)
			(stroke
				(width 0.1)
				(type default)
			)
			(layer "F.Fab")
		)
		(fp_line
			(start -0.12065 0.2794)
			(end -0.12065 0.3048)
			(stroke
				(width 0.1)
				(type default)
			)
			(layer "F.Fab")
		)
		(fp_line
			(start -0.12065 -0.2794)
			(end 0.12065 -0.2794)
			(stroke
				(width 0.1)
				(type default)
			)
			(layer "F.Fab")
		)
		(fp_line
			(start -0.12065 -0.305054)
			(end -0.12065 -0.2794)
			(stroke
				(width 0.1)
				(type default)
			)
			(layer "F.Fab")
		)
		(fp_line
			(start -0.67945 0.3048)
			(end -0.67945 -0.305054)
			(stroke
				(width 0.1)
				(type default)
			)
			(layer "F.Fab")
		)
		(fp_line
			(start -0.67945 -0.305054)
			(end -0.12065 -0.305054)
			(stroke
				(width 0.1)
				(type default)
			)
			(layer "F.Fab")
		)
		(pad "1" smd circle
			(at -0.40005 0 180)
			(size 0 0)
			(layers "F.Cu" "F.Mask" "F.Paste")
			(net "P3V3_NIC7_CO_GATE")
		)
		(pad "2" smd circle
			(at 0.40005 0 180)
			(size 0 0)
			(layers "F.Cu" "F.Mask" "F.Paste")
			(net "GND")
		)
	)
	(footprint ""
		(layer "F.Cu")
		(at 364.552992 -159.173418 90)
		(property "Reference" "PC798"
			(at 0 0 90)
			(layer "F.SilkS")
			(hide yes)
			(effects
				(font
					(size 1.27 1.27)
				)
			)
		)
		(property "Value" ""
			(at 0 0 90)
			(layer "F.Fab")
			(effects
				(font
					(size 1.27 1.27)
				)
			)
		)
		(duplicate_pad_numbers_are_jumpers no)
		(fp_line
			(start 0.7874 -0.4064)
			(end 0.7874 0.4064)
			(stroke
				(width 0.1524)
				(type default)
			)
			(layer "F.SilkS")
		)
		(fp_line
			(start -0.7874 -0.4064)
			(end 0.7874 -0.4064)
			(stroke
				(width 0.1524)
				(type default)
			)
			(layer "F.SilkS")
		)
		(fp_line
			(start 0.7874 0.4064)
			(end -0.7874 0.4064)
			(stroke
				(width 0.1524)
				(type default)
			)
			(layer "F.SilkS")
		)
		(fp_line
			(start -0.7874 0.4064)
			(end -0.7874 -0.4064)
			(stroke
				(width 0.1524)
				(type default)
			)
			(layer "F.SilkS")
		)
		(fp_line
			(start -0.12065 -0.305054)
			(end -0.12065 -0.2794)
			(stroke
				(width 0.1)
				(type default)
			)
			(layer "F.Fab")
		)
		(fp_line
			(start -0.67945 -0.305054)
			(end -0.12065 -0.305054)
			(stroke
				(width 0.1)
				(type default)
			)
			(layer "F.Fab")
		)
		(fp_line
			(start 0.67945 -0.3048)
			(end 0.67945 0.3048)
			(stroke
				(width 0.1)
				(type default)
			)
			(layer "F.Fab")
		)
		(fp_line
			(start 0.12065 -0.3048)
			(end 0.67945 -0.3048)
			(stroke
				(width 0.1)
				(type default)
			)
			(layer "F.Fab")
		)
		(fp_line
			(start 0.12065 -0.2794)
			(end 0.12065 -0.3048)
			(stroke
				(width 0.1)
				(type default)
			)
			(layer "F.Fab")
		)
		(fp_line
			(start -0.12065 -0.2794)
			(end 0.12065 -0.2794)
			(stroke
				(width 0.1)
				(type default)
			)
			(layer "F.Fab")
		)
		(fp_line
			(start 0.120396 0.2794)
			(end -0.12065 0.2794)
			(stroke
				(width 0.1)
				(type default)
			)
			(layer "F.Fab")
		)
		(fp_line
			(start -0.12065 0.2794)
			(end -0.12065 0.3048)
			(stroke
				(width 0.1)
				(type default)
			)
			(layer "F.Fab")
		)
		(fp_line
			(start 0.67945 0.3048)
			(end 0.120396 0.3048)
			(stroke
				(width 0.1)
				(type default)
			)
			(layer "F.Fab")
		)
		(fp_line
			(start 0.120396 0.3048)
			(end 0.120396 0.2794)
			(stroke
				(width 0.1)
				(type default)
			)
			(layer "F.Fab")
		)
		(fp_line
			(start -0.12065 0.3048)
			(end -0.67945 0.3048)
			(stroke
				(width 0.1)
				(type default)
			)
			(layer "F.Fab")
		)
		(fp_line
			(start -0.67945 0.3048)
			(end -0.67945 -0.305054)
			(stroke
				(width 0.1)
				(type default)
			)
			(layer "F.Fab")
		)
		(pad "1" smd circle
			(at -0.40005 0 90)
			(size 0 0)
			(layers "F.Cu" "F.Mask" "F.Paste")
			(net "P12V_AUX")
		)
		(pad "2" smd circle
			(at 0.40005 0 90)
			(size 0 0)
			(layers "F.Cu" "F.Mask" "F.Paste")
			(net "GND")
		)
	)
)
